(kicad_pcb
	(version 20260206)
	(generator "pcbnew")
	(generator_version "10.0")
	(general
		(thickness 1.6)
		(legacy_teardrops no)
	)
	(paper "A4")
	(title_block
		(title "Wiwynn_Tioga_Pass_MB.brd")
		(comment 1 "Tioga Pass / footprints 4168-4174 of 4770")
	)
	(layers
		(0 "F.Cu" signal "TOP")
		(4 "In1.Cu" signal "L2GND")
		(6 "In2.Cu" signal "L3")
		(8 "In3.Cu" signal "L4GND")
		(10 "In4.Cu" signal "L5")
		(12 "In5.Cu" signal "L6GND")
		(14 "In6.Cu" signal "L7VCC")
		(16 "In7.Cu" signal "L8VCC")
		(18 "In8.Cu" signal "L9GND")
		(20 "In9.Cu" signal "L10")
		(22 "In10.Cu" signal "L11GND")
		(24 "In11.Cu" signal "L12")
		(26 "In12.Cu" signal "L13GND")
		(2 "B.Cu" signal "BOTTOM")
		(9 "F.Adhes" user "F.Adhesive")
		(11 "B.Adhes" user "B.Adhesive")
		(13 "F.Paste" user "Package Geometry/Pastemask Top")
		(15 "B.Paste" user "Package Geometry/Pastemask Bottom")
		(5 "F.SilkS" user "Ref Des/Silkscreen Top")
		(7 "B.SilkS" user "Ref Des/Silkscreen Bottom")
		(1 "F.Mask" user "Board Geometry/Soldermask Top")
		(3 "B.Mask" user "Board Geometry/Soldermask Bottom")
		(17 "Dwgs.User" user "User.Drawings")
		(19 "Cmts.User" user "User.Comments")
		(21 "Eco1.User" user "User.Eco1")
		(23 "Eco2.User" user "User.Eco2")
		(25 "Edge.Cuts" user "Board Geometry/Outline")
		(27 "Margin" user)
		(31 "F.CrtYd" user "Package Geometry/Place Bound Top")
		(29 "B.CrtYd" user "Package Geometry/Place Bound Bottom")
		(35 "F.Fab" user "Ref Des/Assembly Top")
		(33 "B.Fab" user "Ref Des/Assembly Bottom")
	)
	(footprint ""
		(layer "B.Cu")
		(at 462.801208 -145.415254)
		(property "Reference" "R1L23"
			(at 0 0 0)
			(layer "B.SilkS")
			(hide yes)
			(effects
				(font
					(size 1.27 1.27)
				)
				(justify mirror)
			)
		)
		(property "Value" ""
			(at 0 0 0)
			(layer "B.Fab")
			(effects
				(font
					(size 1.27 1.27)
				)
				(justify mirror)
			)
		)
		(duplicate_pad_numbers_are_jumpers no)
		(fp_poly
			(pts
				(xy 0.2794 -0.1016) (xy -0.2794 -0.1016) (xy -0.2794 0.9906) (xy 0.2794 0.9906)
			)
			(stroke
				(width 0)
				(type default)
			)
			(fill no)
			(layer "B.CrtYd")
		)
		(fp_line
			(start -0.2794 -0.1016)
			(end 0.2794 -0.1016)
			(stroke
				(width 0.1)
				(type default)
			)
			(layer "B.Fab")
		)
		(fp_line
			(start -0.2794 0.9906)
			(end -0.2794 -0.1016)
			(stroke
				(width 0.1)
				(type default)
			)
			(layer "B.Fab")
		)
		(fp_line
			(start 0.2794 -0.1016)
			(end 0.2794 0.9906)
			(stroke
				(width 0.1)
				(type default)
			)
			(layer "B.Fab")
		)
		(fp_line
			(start 0.2794 0.9906)
			(end -0.2794 0.9906)
			(stroke
				(width 0.1)
				(type default)
			)
			(layer "B.Fab")
		)
		(pad "1" smd rect
			(at 0 0 180)
			(size 0.508 0.508)
			(layers "B.Cu" "B.Mask" "B.Paste")
			(net "XDP_PWRGD_RST_N")
		)
		(pad "2" smd rect
			(at 0 0.889 180)
			(size 0.508 0.508)
			(layers "B.Cu" "B.Mask" "B.Paste")
			(net "P3V3_STBY")
		)
		(zone
			(layer "B.Cu")
			(hatch none 0.5)
			(connect_pads
				(clearance 0)
			)
			(min_thickness 0.25)
			(keepout
				(tracks allowed)
				(vias not_allowed)
				(pads allowed)
				(copperpour not_allowed)
				(footprints allowed)
			)
			(placement
				(enabled no)
				(sheetname "")
			)
			(fill
				(thermal_gap 0.5)
				(thermal_bridge_width 0.5)
				(island_removal_mode 0)
			)
			(polygon
				(pts
					(xy 463.055208 -145.161254) (xy 462.547208 -145.161254) (xy 462.547208 -144.780254) (xy 463.055208 -144.780254)
				)
			)
		)
		(zone
			(layer "B.Cu")
			(hatch none 0.5)
			(connect_pads
				(clearance 0)
			)
			(min_thickness 0.25)
			(keepout
				(tracks not_allowed)
				(vias allowed)
				(pads allowed)
				(copperpour not_allowed)
				(footprints allowed)
			)
			(placement
				(enabled no)
				(sheetname "")
			)
			(fill
				(thermal_gap 0.5)
				(thermal_bridge_width 0.5)
				(island_removal_mode 0)
			)
			(polygon
				(pts
					(xy 463.055208 -144.780254) (xy 462.547208 -144.780254) (xy 462.547208 -145.161254) (xy 463.055208 -145.161254)
				)
			)
		)
	)
	(footprint ""
		(layer "B.Cu")
		(at 333.291688 -124.887482 90)
		(property "Reference" "C4M6"
			(at -0.15367 10.5918 0)
			(unlocked yes)
			(layer "B.SilkS")
			(effects
				(font
					(size 0.7874 0.5842)
					(thickness 0.1524)
				)
				(justify mirror)
			)
		)
		(property "Value" ""
			(at 0 0 90)
			(layer "B.Fab")
			(effects
				(font
					(size 1.27 1.27)
				)
				(justify mirror)
			)
		)
		(duplicate_pad_numbers_are_jumpers no)
		(fp_line
			(start 2.563114 -1.616456)
			(end 2.563114 1.633728)
			(stroke
				(width 0.1524)
				(type default)
			)
			(layer "B.SilkS")
		)
		(fp_line
			(start 1.6002 -1.616456)
			(end 2.563114 -1.616456)
			(stroke
				(width 0.1524)
				(type default)
			)
			(layer "B.SilkS")
		)
		(fp_line
			(start -1.6002 -1.616456)
			(end -2.504948 -1.616456)
			(stroke
				(width 0.1524)
				(type default)
			)
			(layer "B.SilkS")
		)
		(fp_line
			(start -2.504948 -1.616456)
			(end -2.504948 1.633728)
			(stroke
				(width 0.1524)
				(type default)
			)
			(layer "B.SilkS")
		)
		(fp_line
			(start 2.563114 1.633728)
			(end 1.6002 1.633728)
			(stroke
				(width 0.1524)
				(type default)
			)
			(layer "B.SilkS")
		)
		(fp_line
			(start -2.504948 1.633728)
			(end -1.6002 1.633728)
			(stroke
				(width 0.1524)
				(type default)
			)
			(layer "B.SilkS")
		)
		(fp_line
			(start 2.286 7.366)
			(end 2.286 1.632712)
			(stroke
				(width 0.1524)
				(type default)
			)
			(layer "B.SilkS")
		)
		(fp_line
			(start 2.286 7.366)
			(end 1.60147 7.366)
			(stroke
				(width 0.1524)
				(type default)
			)
			(layer "B.SilkS")
		)
		(fp_line
			(start -2.286 7.366)
			(end -2.286 1.63195)
			(stroke
				(width 0.1524)
				(type default)
			)
			(layer "B.SilkS")
		)
		(fp_line
			(start -2.286 7.366)
			(end -1.600708 7.366)
			(stroke
				(width 0.1524)
				(type default)
			)
			(layer "B.SilkS")
		)
		(fp_rect
			(start 2.286 7.366)
			(end -2.286 -0.254)
			(stroke
				(width 0)
				(type default)
			)
			(fill no)
			(layer "B.CrtYd")
		)
		(fp_line
			(start 2.286 -0.254)
			(end -2.286 -0.254)
			(stroke
				(width 0.1)
				(type default)
			)
			(layer "B.Fab")
		)
		(fp_line
			(start -2.286 -0.254)
			(end -2.286 7.366)
			(stroke
				(width 0.1)
				(type default)
			)
			(layer "B.Fab")
		)
		(fp_line
			(start 2.286 7.366)
			(end 2.286 -0.254)
			(stroke
				(width 0.1)
				(type default)
			)
			(layer "B.Fab")
		)
		(fp_line
			(start -2.286 7.366)
			(end 2.286 7.366)
			(stroke
				(width 0.1)
				(type default)
			)
			(layer "B.Fab")
		)
		(pad "1" smd rect
			(at 0 0 270)
			(size 2.54 3.048)
			(layers "B.Cu" "B.Mask" "B.Paste")
			(net "P12V_STBY")
		)
		(pad "2" smd rect
			(at 0 7.112 270)
			(size 2.54 3.048)
			(layers "B.Cu" "B.Mask" "B.Paste")
			(net "GND")
		)
	)
	(footprint ""
		(layer "B.Cu")
		(at 389.33755 -114.25555 180)
		(property "Reference" "C2M19"
			(at 0 0 0)
			(layer "B.SilkS")
			(hide yes)
			(effects
				(font
					(size 1.27 1.27)
				)
				(justify mirror)
			)
		)
		(property "Value" ""
			(at 0 0 0)
			(layer "B.Fab")
			(effects
				(font
					(size 1.27 1.27)
				)
				(justify mirror)
			)
		)
		(duplicate_pad_numbers_are_jumpers no)
		(fp_rect
			(start 0.2794 0.9144)
			(end -0.2794 -0.1143)
			(stroke
				(width 0)
				(type default)
			)
			(fill no)
			(layer "B.CrtYd")
		)
		(fp_line
			(start 0.2794 0.9144)
			(end 0.2794 -0.1143)
			(stroke
				(width 0.1)
				(type default)
			)
			(layer "B.Fab")
		)
		(fp_line
			(start 0.2794 -0.1143)
			(end -0.2794 -0.1143)
			(stroke
				(width 0.1)
				(type default)
			)
			(layer "B.Fab")
		)
		(fp_line
			(start -0.2794 0.9144)
			(end 0.2794 0.9144)
			(stroke
				(width 0.1)
				(type default)
			)
			(layer "B.Fab")
		)
		(fp_line
			(start -0.2794 -0.1143)
			(end -0.2794 0.9144)
			(stroke
				(width 0.1)
				(type default)
			)
			(layer "B.Fab")
		)
		(pad "1" smd custom
			(at 0 0 90)
			(size 0.10414 0.10414)
			(layers "B.Cu" "B.Mask" "B.Paste")
			(net "P1V05_PCH_STBY")
			(options
				(clearance outline)
				(anchor circle)
			)
			(primitives
				(gr_poly
					(pts
						(xy -0.20828 -0.08636) (xy -0.20828 0.08636) (xy -0.08636 0.20828) (xy 0.086614 0.20828) (xy 0.20828 0.086614)
						(xy 0.20828 -0.08636) (xy 0.08636 -0.20828) (xy -0.08636 -0.20828)
					)
					(width 0)
					(fill yes)
				)
			)
		)
		(pad "2" smd custom
			(at 0 0.8001 90)
			(size 0.10414 0.10414)
			(layers "B.Cu" "B.Mask" "B.Paste")
			(net "GND")
			(options
				(clearance outline)
				(anchor circle)
			)
			(primitives
				(gr_poly
					(pts
						(xy -0.20828 -0.08636) (xy -0.20828 0.08636) (xy -0.08636 0.20828) (xy 0.086614 0.20828) (xy 0.20828 0.086614)
						(xy 0.20828 -0.08636) (xy 0.08636 -0.20828) (xy -0.08636 -0.20828)
					)
					(width 0)
					(fill yes)
				)
			)
		)
		(zone
			(layer "B.Cu")
			(hatch none 0.5)
			(connect_pads
				(clearance 0)
			)
			(min_thickness 0.25)
			(keepout
				(tracks allowed)
				(vias not_allowed)
				(pads allowed)
				(copperpour not_allowed)
				(footprints allowed)
			)
			(placement
				(enabled no)
				(sheetname "")
			)
			(fill
				(thermal_gap 0.5)
				(thermal_bridge_width 0.5)
				(island_removal_mode 0)
			)
			(polygon
				(pts
					(xy 389.24992 -114.4651) (xy 389.24992 -114.8461) (xy 389.42518 -114.8461) (xy 389.425434 -114.4651)
				)
			)
		)
		(zone
			(layer "B.Cu")
			(hatch none 0.5)
			(connect_pads
				(clearance 0)
			)
			(min_thickness 0.25)
			(keepout
				(tracks not_allowed)
				(vias allowed)
				(pads allowed)
				(copperpour not_allowed)
				(footprints allowed)
			)
			(placement
				(enabled no)
				(sheetname "")
			)
			(fill
				(thermal_gap 0.5)
				(thermal_bridge_width 0.5)
				(island_removal_mode 0)
			)
			(polygon
				(pts
					(xy 389.24992 -114.4651) (xy 389.24992 -114.8461) (xy 389.42518 -114.8461) (xy 389.425434 -114.4651)
				)
			)
		)
	)
	(footprint ""
		(layer "B.Cu")
		(at 490.5375 -155.3337 -90)
		(property "Reference" "R1L12"
			(at 0 0 90)
			(layer "B.SilkS")
			(hide yes)
			(effects
				(font
					(size 1.27 1.27)
				)
				(justify mirror)
			)
		)
		(property "Value" ""
			(at 0 0 90)
			(layer "B.Fab")
			(effects
				(font
					(size 1.27 1.27)
				)
				(justify mirror)
			)
		)
		(duplicate_pad_numbers_are_jumpers no)
		(fp_poly
			(pts
				(xy 0.2794 -0.1016) (xy -0.2794 -0.1016) (xy -0.2794 0.9906) (xy 0.2794 0.9906)
			)
			(stroke
				(width 0)
				(type default)
			)
			(fill no)
			(layer "B.CrtYd")
		)
		(fp_line
			(start -0.2794 0.9906)
			(end -0.2794 -0.1016)
			(stroke
				(width 0.1)
				(type default)
			)
			(layer "B.Fab")
		)
		(fp_line
			(start 0.2794 0.9906)
			(end -0.2794 0.9906)
			(stroke
				(width 0.1)
				(type default)
			)
			(layer "B.Fab")
		)
		(fp_line
			(start -0.2794 -0.1016)
			(end 0.2794 -0.1016)
			(stroke
				(width 0.1)
				(type default)
			)
			(layer "B.Fab")
		)
		(fp_line
			(start 0.2794 -0.1016)
			(end 0.2794 0.9906)
			(stroke
				(width 0.1)
				(type default)
			)
			(layer "B.Fab")
		)
		(pad "1" smd rect
			(at 0 0 90)
			(size 0.508 0.508)
			(layers "B.Cu" "B.Mask" "B.Paste")
			(net "PWRGD_P3V3")
		)
		(pad "2" smd rect
			(at 0 0.889 90)
			(size 0.508 0.508)
			(layers "B.Cu" "B.Mask" "B.Paste")
			(net "PWRGD_P3V3_R")
		)
		(zone
			(layer "B.Cu")
			(hatch none 0.5)
			(connect_pads
				(clearance 0)
			)
			(min_thickness 0.25)
			(keepout
				(tracks not_allowed)
				(vias allowed)
				(pads allowed)
				(copperpour not_allowed)
				(footprints allowed)
			)
			(placement
				(enabled no)
				(sheetname "")
			)
			(fill
				(thermal_gap 0.5)
				(thermal_bridge_width 0.5)
				(island_removal_mode 0)
			)
			(polygon
				(pts
					(xy 489.9025 -155.0797) (xy 489.9025 -155.5877) (xy 490.2835 -155.5877) (xy 490.2835 -155.0797)
				)
			)
		)
		(zone
			(layer "B.Cu")
			(hatch none 0.5)
			(connect_pads
				(clearance 0)
			)
			(min_thickness 0.25)
			(keepout
				(tracks allowed)
				(vias not_allowed)
				(pads allowed)
				(copperpour not_allowed)
				(footprints allowed)
			)
			(placement
				(enabled no)
				(sheetname "")
			)
			(fill
				(thermal_gap 0.5)
				(thermal_bridge_width 0.5)
				(island_removal_mode 0)
			)
			(polygon
				(pts
					(xy 490.2835 -155.0797) (xy 490.2835 -155.5877) (xy 489.9025 -155.5877) (xy 489.9025 -155.0797)
				)
			)
		)
	)
	(footprint ""
		(layer "B.Cu")
		(at 245.7069 -12.954 -90)
		(property "Reference" "C5G41"
			(at -1.14681 0.76708 0)
			(unlocked yes)
			(layer "B.SilkS")
			(effects
				(font
					(size 0.7874 0.5842)
					(thickness 0.1524)
				)
				(justify mirror)
			)
		)
		(property "Value" ""
			(at 0 0 90)
			(layer "B.Fab")
			(effects
				(font
					(size 1.27 1.27)
				)
				(justify mirror)
			)
		)
		(duplicate_pad_numbers_are_jumpers no)
		(fp_rect
			(start 0.4953 1.6002)
			(end -0.4953 -0.2032)
			(stroke
				(width 0)
				(type default)
			)
			(fill no)
			(layer "B.CrtYd")
		)
		(fp_line
			(start -0.4953 1.6002)
			(end 0.4953 1.6002)
			(stroke
				(width 0.1)
				(type default)
			)
			(layer "B.Fab")
		)
		(fp_line
			(start 0.4953 1.6002)
			(end 0.4953 -0.2032)
			(stroke
				(width 0.1)
				(type default)
			)
			(layer "B.Fab")
		)
		(fp_line
			(start -0.4953 -0.2032)
			(end -0.4953 1.6002)
			(stroke
				(width 0.1)
				(type default)
			)
			(layer "B.Fab")
		)
		(fp_line
			(start 0.4953 -0.2032)
			(end -0.4953 -0.2032)
			(stroke
				(width 0.1)
				(type default)
			)
			(layer "B.Fab")
		)
		(pad "1" smd rect
			(at 0 0 90)
			(size 0.762 0.889)
			(layers "B.Cu" "B.Mask" "B.Paste")
			(net "PVDDQ_ABC")
		)
		(pad "2" smd rect
			(at 0 1.397 90)
			(size 0.762 0.889)
			(layers "B.Cu" "B.Mask" "B.Paste")
			(net "GND")
		)
		(zone
			(layer "B.Cu")
			(hatch none 0.5)
			(connect_pads
				(clearance 0)
			)
			(min_thickness 0.25)
			(keepout
				(tracks not_allowed)
				(vias allowed)
				(pads allowed)
				(copperpour not_allowed)
				(footprints allowed)
			)
			(placement
				(enabled no)
				(sheetname "")
			)
			(fill
				(thermal_gap 0.5)
				(thermal_bridge_width 0.5)
				(island_removal_mode 0)
			)
			(polygon
				(pts
					(xy 244.7544 -12.573) (xy 245.2624 -12.573) (xy 245.2624 -13.335) (xy 244.7544 -13.335)
				)
			)
		)
	)
	(footprint ""
		(layer "B.Cu")
		(at 488.22991 -60.818014 90)
		(property "Reference" "R30W3"
			(at 0.8382 -0.67818 90)
			(unlocked yes)
			(layer "B.SilkS")
			(effects
				(font
					(size 0.4064 0.254)
					(thickness 0.1524)
				)
				(justify left mirror)
			)
		)
		(property "Value" ""
			(at 0 0 90)
			(layer "B.Fab")
			(effects
				(font
					(size 1.27 1.27)
				)
				(justify mirror)
			)
		)
		(duplicate_pad_numbers_are_jumpers no)
		(fp_poly
			(pts
				(xy 0.2794 -0.1016) (xy -0.2794 -0.1016) (xy -0.2794 0.9906) (xy 0.2794 0.9906)
			)
			(stroke
				(width 0)
				(type default)
			)
			(fill no)
			(layer "B.CrtYd")
		)
		(fp_line
			(start 0.2794 -0.1016)
			(end 0.2794 0.9906)
			(stroke
				(width 0.1)
				(type default)
			)
			(layer "B.Fab")
		)
		(fp_line
			(start -0.2794 -0.1016)
			(end 0.2794 -0.1016)
			(stroke
				(width 0.1)
				(type default)
			)
			(layer "B.Fab")
		)
		(fp_line
			(start 0.2794 0.9906)
			(end -0.2794 0.9906)
			(stroke
				(width 0.1)
				(type default)
			)
			(layer "B.Fab")
		)
		(fp_line
			(start -0.2794 0.9906)
			(end -0.2794 -0.1016)
			(stroke
				(width 0.1)
				(type default)
			)
			(layer "B.Fab")
		)
		(pad "1" smd rect
			(at 0 0 270)
			(size 0.508 0.508)
			(layers "B.Cu" "B.Mask" "B.Paste")
			(net "USB3_P01_C_TXN")
		)
		(pad "2" smd rect
			(at 0 0.889 270)
			(size 0.508 0.508)
			(layers "B.Cu" "B.Mask" "B.Paste")
			(net "USB3_P01_FB_TXN")
		)
		(zone
			(layer "B.Cu")
			(hatch none 0.5)
			(connect_pads
				(clearance 0)
			)
			(min_thickness 0.25)
			(keepout
				(tracks allowed)
				(vias not_allowed)
				(pads allowed)
				(copperpour not_allowed)
				(footprints allowed)
			)
			(placement
				(enabled no)
				(sheetname "")
			)
			(fill
				(thermal_gap 0.5)
				(thermal_bridge_width 0.5)
				(island_removal_mode 0)
			)
			(polygon
				(pts
					(xy 488.48391 -61.072014) (xy 488.48391 -60.564014) (xy 488.86491 -60.564014) (xy 488.86491 -61.072014)
				)
			)
		)
		(zone
			(layer "B.Cu")
			(hatch none 0.5)
			(connect_pads
				(clearance 0)
			)
			(min_thickness 0.25)
			(keepout
				(tracks not_allowed)
				(vias allowed)
				(pads allowed)
				(copperpour not_allowed)
				(footprints allowed)
			)
			(placement
				(enabled no)
				(sheetname "")
			)
			(fill
				(thermal_gap 0.5)
				(thermal_bridge_width 0.5)
				(island_removal_mode 0)
			)
			(polygon
				(pts
					(xy 488.86491 -61.072014) (xy 488.86491 -60.564014) (xy 488.48391 -60.564014) (xy 488.48391 -61.072014)
				)
			)
		)
	)
	(footprint ""
		(layer "B.Cu")
		(at 282.259024 -72.679814 -90)
		(property "Reference" "R4P10"
			(at 0 0 90)
			(layer "B.SilkS")
			(hide yes)
			(effects
				(font
					(size 1.27 1.27)
				)
				(justify mirror)
			)
		)
		(property "Value" ""
			(at 0 0 90)
			(layer "B.Fab")
			(effects
				(font
					(size 1.27 1.27)
				)
				(justify mirror)
			)
		)
		(duplicate_pad_numbers_are_jumpers no)
		(fp_rect
			(start 0.2794 0.9906)
			(end -0.2794 -0.1016)
			(stroke
				(width 0)
				(type default)
			)
			(fill no)
			(layer "B.CrtYd")
		)
		(fp_line
			(start -0.2794 0.9906)
			(end -0.2794 -0.1016)
			(stroke
				(width 0.1)
				(type default)
			)
			(layer "B.Fab")
		)
		(fp_line
			(start 0.2794 0.9906)
			(end -0.2794 0.9906)
			(stroke
				(width 0.1)
				(type default)
			)
			(layer "B.Fab")
		)
		(fp_line
			(start -0.2794 -0.1016)
			(end 0.2794 -0.1016)
			(stroke
				(width 0.1)
				(type default)
			)
			(layer "B.Fab")
		)
		(fp_line
			(start 0.2794 -0.1016)
			(end 0.2794 0.9906)
			(stroke
				(width 0.1)
				(type default)
			)
			(layer "B.Fab")
		)
		(pad "1" smd rect
			(at 0 0 90)
			(size 0.508 0.508)
			(layers "B.Cu" "B.Mask" "B.Paste")
			(net "A_CPU0_ABC_RCOMP1")
		)
		(pad "2" smd rect
			(at 0 0.889 90)
			(size 0.508 0.508)
			(layers "B.Cu" "B.Mask" "B.Paste")
			(net "GND")
		)
		(zone
			(layer "B.Cu")
			(hatch none 0.5)
			(connect_pads
				(clearance 0)
			)
			(min_thickness 0.25)
			(keepout
				(tracks allowed)
				(vias not_allowed)
				(pads allowed)
				(copperpour not_allowed)
				(footprints allowed)
			)
			(placement
				(enabled no)
				(sheetname "")
			)
			(fill
				(thermal_gap 0.5)
				(thermal_bridge_width 0.5)
				(island_removal_mode 0)
			)
			(polygon
				(pts
					(xy 281.624024 -72.425814) (xy 282.005024 -72.425814) (xy 282.005024 -72.933814) (xy 281.624024 -72.933814)
				)
			)
		)
		(zone
			(layer "B.Cu")
			(hatch none 0.5)
			(connect_pads
				(clearance 0)
			)
			(min_thickness 0.25)
			(keepout
				(tracks not_allowed)
				(vias allowed)
				(pads allowed)
				(copperpour not_allowed)
				(footprints allowed)
			)
			(placement
				(enabled no)
				(sheetname "")
			)
			(fill
				(thermal_gap 0.5)
				(thermal_bridge_width 0.5)
				(island_removal_mode 0)
			)
			(polygon
				(pts
					(xy 281.624024 -72.425814) (xy 282.005024 -72.425814) (xy 282.005024 -72.933814) (xy 281.624024 -72.933814)
				)
			)
		)
	)
)
